FILE_TYPE=LIBRARY_PARTS;
primitive 'TMP421','TMP421_TSSOP';
  pin
    'A'<1>:
      PIN_NUMBER='(3)';
      INPUT_LOAD='(-0.01,0.01)';
    'A'<0>:
      PIN_NUMBER='(4)';
      INPUT_LOAD='(-0.01,0.01)';
    'DXN':
      PIN_NUMBER='(2)';
      INPUT_LOAD='(-0.01,0.01)';
    'DXP':
      PIN_NUMBER='(1)';
      INPUT_LOAD='(-0.01,0.01)';
    'GND':
      PIN_NUMBER='(5)';
      PINUSE='GROUND';
      NO_LOAD_CHECK='Both';
      NO_IO_CHECK='Both';
      NO_ASSERT_CHECK='TRUE';
      NO_DIR_CHECK='TRUE';
      ALLOW_CONNECT='TRUE';
    'SCL':
      PIN_NUMBER='(7)';
      BIDIRECTIONAL='TRUE';
      INPUT_LOAD='(-0.01,0.01)';
      OUTPUT_LOAD='(1.0,-1.0)';
    'SDA':
      PIN_NUMBER='(6)';
      BIDIRECTIONAL='TRUE';
      INPUT_LOAD='(-0.01,0.01)';
      OUTPUT_LOAD='(1.0,-1.0)';
    'VP':
      PIN_NUMBER='(8)';
      PINUSE='POWER';
      NO_LOAD_CHECK='Both';
      NO_IO_CHECK='Both';
      NO_ASSERT_CHECK='TRUE';
      NO_DIR_CHECK='TRUE';
      ALLOW_CONNECT='TRUE';
  end_pin;
  body
    PART_NAME='TMP421';
    PHYS_DES_PREFIX='U';
  end_body;
end_primitive;

END.
